(kicad_pcb
	(version 20260206)
	(generator "pcbnew")
	(generator_version "10.0")
	(general
		(thickness 1.21888)
		(legacy_teardrops no)
	)
	(paper "A4")
	(title_block
		(title "timecard-v8 — TimeCard-DC-V8_EXP.PcbDoc")
		(comment 1 "Time Appliance Project (Time Card) / footprints 30-39 of 288")
	)
	(layers
		(0 "F.Cu" signal "TOP")
		(4 "In1.Cu" signal "SGND")
		(6 "In2.Cu" signal "IN1")
		(8 "In3.Cu" signal "IN2")
		(10 "In4.Cu" signal "SGND1")
		(2 "B.Cu" signal "BOTTOM")
		(9 "F.Adhes" user "F.Adhesive")
		(11 "B.Adhes" user "B.Adhesive")
		(13 "F.Paste" user "Top Paste")
		(15 "B.Paste" user "Bottom Paste")
		(5 "F.SilkS" user "Top Overlay")
		(7 "B.SilkS" user "Bottom Overlay")
		(1 "F.Mask" user "Top Solder")
		(3 "B.Mask" user "Bottom Solder")
		(17 "Dwgs.User" user "User.Drawings")
		(19 "Cmts.User" user "User.Comments")
		(21 "Eco1.User" user "User.Eco1")
		(23 "Eco2.User" user "User.Eco2")
		(25 "Edge.Cuts" user)
		(27 "Margin" user)
		(31 "F.CrtYd" user "Top Courtyard")
		(29 "B.CrtYd" user "Bottom Courtyard")
		(35 "F.Fab" user "Top Component Center")
		(33 "B.Fab" user "Bottom Component Center")
	)
	(footprint "Vault:FP-STPS5L60S-MFG"
		(layer "F.Cu")
		(at 221.9261 97.9162)
		(property "Reference" "D19"
			(at 0.2286 -3.773069 0)
			(unlocked yes)
			(layer "F.SilkS")
			(effects
				(font
					(size 0.762 0.762)
					(thickness 0.2286)
				)
			)
		)
		(property "Value" "STPS5L60S"
			(at -6.491471 3.76976 270)
			(unlocked yes)
			(layer "F.SilkS")
			(hide yes)
			(effects
				(font
					(size 0.762 0.762)
					(thickness 0.2286)
				)
			)
		)
		(sheetname "POWER")
		(sheetfile "POWER.kicad_sch")
		(duplicate_pad_numbers_are_jumpers no)
		(fp_line
			(start -3.575 -3.125)
			(end 3.575 -3.125)
			(stroke
				(width 0.2)
				(type solid)
			)
			(layer "F.SilkS")
		)
		(fp_line
			(start -3.575 -2.025)
			(end -3.575 -3.125)
			(stroke
				(width 0.2)
				(type solid)
			)
			(layer "F.SilkS")
		)
		(fp_line
			(start -3.575 3.125)
			(end -3.575 2.025)
			(stroke
				(width 0.2)
				(type solid)
			)
			(layer "F.SilkS")
		)
		(fp_line
			(start -3.575 3.125)
			(end 3.575 3.125)
			(stroke
				(width 0.2)
				(type solid)
			)
			(layer "F.SilkS")
		)
		(fp_line
			(start 3.575 -2.025)
			(end 3.575 -3.125)
			(stroke
				(width 0.2)
				(type solid)
			)
			(layer "F.SilkS")
		)
		(fp_line
			(start 3.575 3.125)
			(end 3.575 2.025)
			(stroke
				(width 0.2)
				(type solid)
			)
			(layer "F.SilkS")
		)
		(fp_circle
			(center -4.7 -0.025)
			(end -4.7 -0.15)
			(stroke
				(width 0.25)
				(type solid)
			)
			(fill no)
			(layer "F.SilkS")
		)
		(fp_line
			(start -4.195 -3.225)
			(end 4.195 -3.225)
			(stroke
				(width 0.2)
				(type solid)
			)
			(layer "F.CrtYd")
		)
		(fp_line
			(start -4.195 3.225)
			(end -4.195 -3.225)
			(stroke
				(width 0.2)
				(type solid)
			)
			(layer "F.CrtYd")
		)
		(fp_line
			(start -4.195 3.225)
			(end 4.195 3.225)
			(stroke
				(width 0.2)
				(type solid)
			)
			(layer "F.CrtYd")
		)
		(fp_line
			(start 4.195 3.225)
			(end 4.195 -3.225)
			(stroke
				(width 0.2)
				(type solid)
			)
			(layer "F.CrtYd")
		)
		(fp_line
			(start -4.195 -3.225)
			(end 4.195 -3.225)
			(stroke
				(width 0.2)
				(type solid)
			)
			(layer "F.Fab")
		)
		(fp_line
			(start -4.195 3.225)
			(end -4.195 -3.225)
			(stroke
				(width 0.2)
				(type solid)
			)
			(layer "F.Fab")
		)
		(fp_line
			(start -4.195 3.225)
			(end 4.195 3.225)
			(stroke
				(width 0.2)
				(type solid)
			)
			(layer "F.Fab")
		)
		(fp_line
			(start -0.5 0)
			(end 0.5 0)
			(stroke
				(width 0.1)
				(type solid)
			)
			(layer "F.Fab")
		)
		(fp_line
			(start 0 0.5)
			(end 0 -0.5)
			(stroke
				(width 0.1)
				(type solid)
			)
			(layer "F.Fab")
		)
		(fp_line
			(start 4.195 3.225)
			(end 4.195 -3.225)
			(stroke
				(width 0.2)
				(type solid)
			)
			(layer "F.Fab")
		)
		(fp_text user "${REFERENCE}"
			(at -0.00001 0.09602 360)
			(unlocked yes)
			(layer "F.Fab")
			(effects
				(font
					(face "Arial")
					(size 0.63 0.63)
					(thickness 0.1)
				)
				(justify left bottom)
			)
		)
		(pad "1" smd rect
			(at -3.325 0)
			(size 1.54 3.14)
			(layers "F.Cu" "F.Mask" "F.Paste")
			(net "NetD12_1")
			(solder_mask_margin 0)
			(solder_paste_margin 0)
		)
		(pad "2" smd rect
			(at 3.325 0)
			(size 1.54 3.14)
			(layers "F.Cu" "F.Mask" "F.Paste")
			(net "+12V_PCIE")
			(solder_mask_margin 0)
			(solder_paste_margin 0)
		)
	)
	(footprint "SA53:SolderSocket"
		(layer "F.Cu")
		(at 99.3261 94.9162 90)
		(property "Reference" "SKT2"
			(at -0.226921 -6.7714 0)
			(unlocked yes)
			(layer "F.SilkS")
			(effects
				(font
					(size 0.762 0.762)
					(thickness 0.2286)
				)
			)
		)
		(property "Value" "0332-0-43-80-18-27-10-0"
			(at -2.910071 16.1362 0)
			(unlocked yes)
			(layer "F.SilkS")
			(hide yes)
			(effects
				(font
					(size 0.762 0.762)
					(thickness 0.2286)
				)
			)
		)
		(sheetname "MAC")
		(sheetfile "MAC.kicad_sch")
		(duplicate_pad_numbers_are_jumpers no)
		(pad "1" thru_hole circle
			(at 0 0 90)
			(size 2.54 2.54)
			(drill 2.0066)
			(layers "*.Cu" "*.Mask")
			(remove_unused_layers no)
			(net "MAC_FREQ_CTRL")
			(thermal_bridge_angle 90)
		)
	)
	(footprint "Connectors:SAMTEC_HTST-105-01-L-DV-A"
		(layer "F.Cu")
		(at 212.8061 138.9462)
		(property "Reference" "U5"
			(at -10.386655 -2.43 90)
			(unlocked yes)
			(layer "F.SilkS")
			(effects
				(font
					(size 0.762 0.762)
					(thickness 0.2286)
				)
				(justify left bottom)
			)
		)
		(property "Value" "HTST-105-01-L-DV-A"
			(at -0.5217 18.090245 0)
			(unlocked yes)
			(layer "F.SilkS")
			(hide yes)
			(effects
				(font
					(size 0.762 0.762)
					(thickness 0.2286)
				)
				(justify left bottom)
			)
		)
		(sheetname "PCIe_JTAG")
		(sheetfile "PCIe_JTAG.kicad_sch")
		(duplicate_pad_numbers_are_jumpers no)
		(fp_line
			(start -10.16 -4.635)
			(end -6.065 -4.635)
			(stroke
				(width 0.2)
				(type solid)
			)
			(layer "F.SilkS")
		)
		(fp_line
			(start -10.16 4.635)
			(end -10.16 -4.635)
			(stroke
				(width 0.2)
				(type solid)
			)
			(layer "F.SilkS")
		)
		(fp_line
			(start -10.16 4.635)
			(end -6.065 4.635)
			(stroke
				(width 0.2)
				(type solid)
			)
			(layer "F.SilkS")
		)
		(fp_line
			(start 6.065 -4.635)
			(end 10.16 -4.635)
			(stroke
				(width 0.2)
				(type solid)
			)
			(layer "F.SilkS")
		)
		(fp_line
			(start 6.065 4.635)
			(end 10.16 4.635)
			(stroke
				(width 0.2)
				(type solid)
			)
			(layer "F.SilkS")
		)
		(fp_line
			(start 10.16 4.635)
			(end 10.16 -4.635)
			(stroke
				(width 0.2)
				(type solid)
			)
			(layer "F.SilkS")
		)
		(fp_circle
			(center -7.62 5.715)
			(end -7.62 5.08)
			(stroke
				(width 0.2)
				(type solid)
			)
			(fill no)
			(layer "F.SilkS")
		)
		(pad "" np_thru_hole circle
			(at -3.81 0)
			(size 1.676 1.676)
			(drill 1.676)
			(layers "*.Cu" "*.Mask")
			(thermal_bridge_angle 90)
		)
		(pad "" np_thru_hole circle
			(at 3.81 0)
			(size 1.676 1.676)
			(drill 1.676)
			(layers "*.Cu" "*.Mask")
			(thermal_bridge_angle 90)
		)
		(pad "1" smd rect
			(at -5.08 3.43)
			(size 1.27 5.08)
			(layers "F.Cu" "F.Mask" "F.Paste")
			(net "NetR18_2")
		)
		(pad "2" smd rect
			(at -5.08 -3.43)
			(size 1.27 5.08)
			(layers "F.Cu" "F.Mask" "F.Paste")
			(net "GND")
		)
		(pad "3" smd rect
			(at -2.54 3.43)
			(size 1.27 5.08)
			(layers "F.Cu" "F.Mask" "F.Paste")
			(net "NetR19_2")
		)
		(pad "4" smd rect
			(at -2.54 -3.43)
			(size 1.27 5.08)
			(layers "F.Cu" "F.Mask" "F.Paste")
			(net "+3.3V")
		)
		(pad "5" smd rect
			(at 0 3.43)
			(size 1.27 5.08)
			(layers "F.Cu" "F.Mask" "F.Paste")
			(net "NetR20_2")
		)
		(pad "6" smd rect
			(at 0 -3.43)
			(size 1.27 5.08)
			(layers "F.Cu" "F.Mask" "F.Paste")
			(net "+3.3V")
		)
		(pad "7" smd rect
			(at 2.54 3.43)
			(size 1.27 5.08)
			(layers "F.Cu" "F.Mask" "F.Paste")
		)
		(pad "8" smd rect
			(at 2.54 -3.43)
			(size 1.27 5.08)
			(layers "F.Cu" "F.Mask" "F.Paste")
		)
		(pad "9" smd rect
			(at 5.08 3.43)
			(size 1.27 5.08)
			(layers "F.Cu" "F.Mask" "F.Paste")
			(net "NetR21_2")
		)
		(pad "10" smd rect
			(at 5.08 -3.43)
			(size 1.27 5.08)
			(layers "F.Cu" "F.Mask" "F.Paste")
			(net "GND")
		)
	)
	(footprint "Vault:RESC1608X55X25LL10T15"
		(layer "F.Cu")
		(at 130.9261 87.9162)
		(property "Reference" "R11"
			(at 0.128605 1.126931 0)
			(unlocked yes)
			(layer "F.SilkS")
			(effects
				(font
					(size 0.762 0.762)
					(thickness 0.2286)
				)
			)
		)
		(property "Value" "4.7K"
			(at -2.630671 2.57724 270)
			(unlocked yes)
			(layer "F.SilkS")
			(hide yes)
			(effects
				(font
					(size 0.762 0.762)
					(thickness 0.2286)
				)
			)
		)
		(sheetname "MAC")
		(sheetfile "MAC.kicad_sch")
		(duplicate_pad_numbers_are_jumpers no)
		(pad "1" smd rect
			(at -0.65 0 90)
			(size 0.8 0.6)
			(layers "F.Cu" "F.Mask" "F.Paste")
			(net "GND")
		)
		(pad "2" smd rect
			(at 0.65 0 90)
			(size 0.8 0.6)
			(layers "F.Cu" "F.Mask" "F.Paste")
			(net "FPGA_MAC_PPS_DIFF_IN0")
		)
	)
	(footprint "Vault:CAPC1608X87X45ML20T05"
		(layer "F.Cu")
		(at 88.1261 79.3286 90)
		(property "Reference" "C61"
			(at -1.25 3.593345 90)
			(unlocked yes)
			(layer "F.SilkS")
			(effects
				(font
					(size 0.762 0.762)
					(thickness 0.2286)
				)
				(justify left bottom)
			)
		)
		(property "Value" "0.1uF"
			(at -3.382645 -0.2921 0)
			(unlocked yes)
			(layer "F.SilkS")
			(hide yes)
			(effects
				(font
					(size 0.762 0.762)
					(thickness 0.2286)
				)
				(justify left bottom)
			)
		)
		(sheetname "GPS_IMU_SENSORS")
		(sheetfile "GPS_IMU_SENSORS.kicad_sch")
		(duplicate_pad_numbers_are_jumpers no)
		(pad "1" smd rect
			(at -0.7 0 180)
			(size 1.1 1.05)
			(layers "F.Cu" "F.Mask" "F.Paste")
			(net "GND")
		)
		(pad "2" smd rect
			(at 0.7 0 180)
			(size 1.1 1.05)
			(layers "F.Cu" "F.Mask" "F.Paste")
			(net "+5.0V")
		)
	)
	(footprint "Vault:FP-MK212BG-MFG"
		(layer "F.Cu")
		(at 218.8761 60.5786 180)
		(property "Reference" "C34"
			(at 3.0214 -0.026921 0)
			(unlocked yes)
			(layer "F.SilkS")
			(effects
				(font
					(size 0.762 0.762)
					(thickness 0.2286)
				)
			)
		)
		(property "Value" "10uF"
			(at -3.240271 2.22164 90)
			(unlocked yes)
			(layer "F.SilkS")
			(hide yes)
			(effects
				(font
					(size 0.762 0.762)
					(thickness 0.2286)
				)
			)
		)
		(sheetname "GPS_IMU_SENSORS")
		(sheetfile "GPS_IMU_SENSORS.kicad_sch")
		(duplicate_pad_numbers_are_jumpers no)
		(fp_line
			(start 0.125 0.725)
			(end -0.125 0.725)
			(stroke
				(width 0.2)
				(type solid)
			)
			(layer "F.SilkS")
		)
		(fp_line
			(start 0.125 -0.725)
			(end -0.125 -0.725)
			(stroke
				(width 0.2)
				(type solid)
			)
			(layer "F.SilkS")
		)
		(fp_line
			(start 1.6 0.825)
			(end -1.6 0.825)
			(stroke
				(width 0.2)
				(type solid)
			)
			(layer "F.CrtYd")
		)
		(fp_line
			(start 1.6 -0.825)
			(end 1.6 0.825)
			(stroke
				(width 0.2)
				(type solid)
			)
			(layer "F.CrtYd")
		)
		(fp_line
			(start 1.6 -0.825)
			(end -1.6 -0.825)
			(stroke
				(width 0.2)
				(type solid)
			)
			(layer "F.CrtYd")
		)
		(fp_line
			(start -1.6 -0.825)
			(end -1.6 0.825)
			(stroke
				(width 0.2)
				(type solid)
			)
			(layer "F.CrtYd")
		)
		(fp_line
			(start 1.6 0.825)
			(end -1.6 0.825)
			(stroke
				(width 0.2)
				(type solid)
			)
			(layer "F.Fab")
		)
		(fp_line
			(start 1.6 -0.825)
			(end 1.6 0.825)
			(stroke
				(width 0.2)
				(type solid)
			)
			(layer "F.Fab")
		)
		(fp_line
			(start 1.6 -0.825)
			(end -1.6 -0.825)
			(stroke
				(width 0.2)
				(type solid)
			)
			(layer "F.Fab")
		)
		(fp_line
			(start 0.5 0)
			(end -0.5 0)
			(stroke
				(width 0.1)
				(type solid)
			)
			(layer "F.Fab")
		)
		(fp_line
			(start 0 -0.5)
			(end 0 0.5)
			(stroke
				(width 0.1)
				(type solid)
			)
			(layer "F.Fab")
		)
		(fp_line
			(start -1.6 -0.825)
			(end -1.6 0.825)
			(stroke
				(width 0.2)
				(type solid)
			)
			(layer "F.Fab")
		)
		(fp_text user "${REFERENCE}"
			(at -0.00001 0.09602 180)
			(unlocked yes)
			(layer "F.Fab")
			(effects
				(font
					(face "Arial")
					(size 0.63 0.63)
					(thickness 0.1)
				)
				(justify left bottom)
			)
		)
		(pad "1" smd rect
			(at -1 0 180)
			(size 1 1.25)
			(layers "F.Cu" "F.Mask" "F.Paste")
			(net "+3.3V")
			(solder_mask_margin 0)
			(solder_paste_margin 0)
		)
		(pad "2" smd rect
			(at 1 0 180)
			(size 1 1.25)
			(layers "F.Cu" "F.Mask" "F.Paste")
			(net "GND")
			(solder_mask_margin 0)
			(solder_paste_margin 0)
		)
	)
	(footprint "Vault:CAPC1608X87X45ML20T05"
		(layer "F.Cu")
		(at 80.6261 125.8662 -90)
		(property "Reference" "C27"
			(at 2.7714 -0.026931 90)
			(unlocked yes)
			(layer "F.SilkS")
			(effects
				(font
					(size 0.762 0.762)
					(thickness 0.2286)
				)
			)
		)
		(property "Value" "0.1uF"
			(at 2.069035 2.630671 270)
			(unlocked yes)
			(layer "F.SilkS")
			(hide yes)
			(effects
				(font
					(size 0.762 0.762)
					(thickness 0.2286)
				)
			)
		)
		(sheetname "USER_IO")
		(sheetfile "USER_IO.kicad_sch")
		(duplicate_pad_numbers_are_jumpers no)
		(pad "1" smd rect
			(at -0.7 0)
			(size 1.1 1.05)
			(layers "F.Cu" "F.Mask" "F.Paste")
			(net "+3.3V")
		)
		(pad "2" smd rect
			(at 0.7 0)
			(size 1.1 1.05)
			(layers "F.Cu" "F.Mask" "F.Paste")
			(net "GND")
		)
	)
	(footprint "Vault:CAPC1608X87X45ML20T05"
		(layer "F.Cu")
		(at 92.1261 74.5786 90)
		(property "Reference" "C59"
			(at -4.25 1.343345 90)
			(unlocked yes)
			(layer "F.SilkS")
			(effects
				(font
					(size 0.762 0.762)
					(thickness 0.2286)
				)
				(justify left bottom)
			)
		)
		(property "Value" "0.1uF"
			(at -3.382645 -0.2921 0)
			(unlocked yes)
			(layer "F.SilkS")
			(hide yes)
			(effects
				(font
					(size 0.762 0.762)
					(thickness 0.2286)
				)
				(justify left bottom)
			)
		)
		(sheetname "GPS_IMU_SENSORS")
		(sheetfile "GPS_IMU_SENSORS.kicad_sch")
		(duplicate_pad_numbers_are_jumpers no)
		(pad "1" smd rect
			(at -0.7 0 180)
			(size 1.1 1.05)
			(layers "F.Cu" "F.Mask" "F.Paste")
			(net "GND")
		)
		(pad "2" smd rect
			(at 0.7 0 180)
			(size 1.1 1.05)
			(layers "F.Cu" "F.Mask" "F.Paste")
			(net "+3.3V")
		)
	)
	(footprint "Vault:FP-CC0402-MFG"
		(layer "F.Cu")
		(at 235.7261 63.2162 90)
		(property "Reference" "C91"
			(at 0.428605 -1.773079 90)
			(unlocked yes)
			(layer "F.SilkS")
			(effects
				(font
					(size 0.762 0.762)
					(thickness 0.2286)
				)
			)
		)
		(property "Value" "10nF_50V_0402"
			(at 9.02662 2.389351 90)
			(unlocked yes)
			(layer "F.SilkS")
			(hide yes)
			(effects
				(font
					(size 0.762 0.762)
					(thickness 0.2286)
				)
			)
		)
		(sheetname "USBUart_DipSelects")
		(sheetfile "USBUart_DipSelects.kicad_sch")
		(duplicate_pad_numbers_are_jumpers no)
		(fp_line
			(start -0.525 -0.675)
			(end 0.525 -0.675)
			(stroke
				(width 0.2)
				(type solid)
			)
			(layer "F.SilkS")
		)
		(fp_line
			(start -0.53033 0.68067)
			(end 0.51967 0.68067)
			(stroke
				(width 0.2)
				(type solid)
			)
			(layer "F.SilkS")
		)
		(fp_line
			(start 0.875 -0.475)
			(end 0.875 0.475)
			(stroke
				(width 0.2)
				(type solid)
			)
			(layer "F.CrtYd")
		)
		(fp_line
			(start -0.875 -0.475)
			(end 0.875 -0.475)
			(stroke
				(width 0.2)
				(type solid)
			)
			(layer "F.CrtYd")
		)
		(fp_line
			(start -0.875 -0.475)
			(end -0.875 0.475)
			(stroke
				(width 0.2)
				(type solid)
			)
			(layer "F.CrtYd")
		)
		(fp_line
			(start -0.875 0.475)
			(end 0.875 0.475)
			(stroke
				(width 0.2)
				(type solid)
			)
			(layer "F.CrtYd")
		)
		(fp_line
			(start 0 -0.5)
			(end 0 0.5)
			(stroke
				(width 0.1)
				(type solid)
			)
			(layer "F.Fab")
		)
		(fp_line
			(start 0.875 -0.475)
			(end 0.875 0.475)
			(stroke
				(width 0.2)
				(type solid)
			)
			(layer "F.Fab")
		)
		(fp_line
			(start -0.875 -0.475)
			(end 0.875 -0.475)
			(stroke
				(width 0.2)
				(type solid)
			)
			(layer "F.Fab")
		)
		(fp_line
			(start -0.875 -0.475)
			(end -0.875 0.475)
			(stroke
				(width 0.2)
				(type solid)
			)
			(layer "F.Fab")
		)
		(fp_line
			(start -0.5 0)
			(end 0.5 0)
			(stroke
				(width 0.1)
				(type solid)
			)
			(layer "F.Fab")
		)
		(fp_line
			(start -0.875 0.475)
			(end 0.875 0.475)
			(stroke
				(width 0.2)
				(type solid)
			)
			(layer "F.Fab")
		)
		(fp_text user "${REFERENCE}"
			(at -0.00001 0.09601 90)
			(unlocked yes)
			(layer "F.Fab")
			(effects
				(font
					(face "Arial")
					(size 0.63 0.63)
					(thickness 0.1)
				)
				(justify left bottom)
			)
		)
		(pad "1" smd rect
			(at -0.5 0 90)
			(size 0.5 0.5)
			(layers "F.Cu" "F.Mask" "F.Paste")
			(net "NetC91_1")
			(solder_mask_margin 0)
			(solder_paste_margin 0)
		)
		(pad "2" smd rect
			(at 0.5 0 90)
			(size 0.5 0.5)
			(layers "F.Cu" "F.Mask" "F.Paste")
			(net "GND")
			(solder_mask_margin 0)
			(solder_paste_margin 0)
		)
	)
	(footprint "Vault:M08A_L"
		(layer "F.Cu")
		(at 118.6261 86.0786)
		(property "Reference" "U4"
			(at 1.028595 -3.235469 0)
			(unlocked yes)
			(layer "F.SilkS")
			(effects
				(font
					(size 0.762 0.762)
					(thickness 0.2286)
				)
			)
		)
		(property "Value" "DS90LV028AQMA"
			(at 6.71518 4.180071 0)
			(unlocked yes)
			(layer "F.SilkS")
			(hide yes)
			(effects
				(font
					(size 0.762 0.762)
					(thickness 0.2286)
				)
			)
		)
		(sheetname "MAC")
		(sheetfile "MAC.kicad_sch")
		(duplicate_pad_numbers_are_jumpers no)
		(fp_line
			(start -1 -2.5)
			(end 1 -2.5)
			(stroke
				(width 0.2)
				(type solid)
			)
			(layer "F.SilkS")
		)
		(fp_line
			(start -1 2.5)
			(end -1 -2.5)
			(stroke
				(width 0.2)
				(type solid)
			)
			(layer "F.SilkS")
		)
		(fp_line
			(start -1 2.5)
			(end 1 2.5)
			(stroke
				(width 0.2)
				(type solid)
			)
			(layer "F.SilkS")
		)
		(fp_line
			(start 1 2.5)
			(end 1 -2.5)
			(stroke
				(width 0.2)
				(type solid)
			)
			(layer "F.SilkS")
		)
		(fp_circle
			(center -2.35 -2.755)
			(end -2.35 -2.88)
			(stroke
				(width 0.25)
				(type solid)
			)
			(fill no)
			(layer "F.SilkS")
		)
		(fp_circle
			(center -0.2 -1.7)
			(end -0.2 -1.9)
			(stroke
				(width 0.4)
				(type solid)
			)
			(fill no)
			(layer "F.SilkS")
		)
		(pad "1" smd oval
			(at -2.35 -1.905 90)
			(size 0.6 1.9)
			(layers "F.Cu" "F.Mask" "F.Paste")
			(net "MAC_PPS_OUT-")
		)
		(pad "2" smd oval
			(at -2.35 -0.635 90)
			(size 0.6 1.9)
			(layers "F.Cu" "F.Mask" "F.Paste")
			(net "MAC_PPS_OUT+")
		)
		(pad "3" smd oval
			(at -2.35 0.635 90)
			(size 0.6 1.9)
			(layers "F.Cu" "F.Mask" "F.Paste")
		)
		(pad "4" smd oval
			(at -2.35 1.905 90)
			(size 0.6 1.9)
			(layers "F.Cu" "F.Mask" "F.Paste")
		)
		(pad "5" smd oval
			(at 2.35 1.905 90)
			(size 0.6 1.9)
			(layers "F.Cu" "F.Mask" "F.Paste")
			(net "GND")
		)
		(pad "6" smd oval
			(at 2.35 0.635 90)
			(size 0.6 1.9)
			(layers "F.Cu" "F.Mask" "F.Paste")
		)
		(pad "7" smd oval
			(at 2.35 -0.635 90)
			(size 0.6 1.9)
			(layers "F.Cu" "F.Mask" "F.Paste")
			(net "FPGA_MAC_PPSDIFF_OUT")
		)
		(pad "8" smd oval
			(at 2.35 -1.905 90)
			(size 0.6 1.9)
			(layers "F.Cu" "F.Mask" "F.Paste")
			(net "+3.3V")
		)
	)
)
